(kicad_pcb
	(version 20260206)
	(generator "pcbnew")
	(generator_version "10.0")
	(general
		(thickness 1.6)
		(legacy_teardrops no)
	)
	(paper "A4")
	(title_block
		(title "04192023_DAF0TMB3IC0_F0TG_MB_C_brd_V02_OCP.brd")
		(comment 1 "Grand Teton / footprints 4758-4760 of 8354")
	)
	(layers
		(0 "F.Cu" signal "TOP")
		(4 "In1.Cu" signal "GND")
		(6 "In2.Cu" signal "IN1")
		(8 "In3.Cu" signal "GND1")
		(10 "In4.Cu" signal "IN2")
		(12 "In5.Cu" signal "GND2")
		(14 "In6.Cu" signal "IN3")
		(16 "In7.Cu" signal "GND3")
		(18 "In8.Cu" signal "VCC")
		(20 "In9.Cu" signal "VCC1")
		(22 "In10.Cu" signal "GND4")
		(24 "In11.Cu" signal "IN4")
		(26 "In12.Cu" signal "GND5")
		(28 "In13.Cu" signal "IN5")
		(30 "In14.Cu" signal "GND6")
		(32 "In15.Cu" signal "IN6")
		(34 "In16.Cu" signal "GND7")
		(2 "B.Cu" signal "BOTTOM")
		(9 "F.Adhes" user "F.Adhesive")
		(11 "B.Adhes" user "B.Adhesive")
		(13 "F.Paste" user "Package Geometry/Pastemask Top")
		(15 "B.Paste" user "Package Geometry/Pastemask Bottom")
		(5 "F.SilkS" user "Ref Des/Silkscreen Top")
		(7 "B.SilkS" user "Ref Des/Silkscreen Bottom")
		(1 "F.Mask" user "Board Geometry/Soldermask Top")
		(3 "B.Mask" user "Board Geometry/Soldermask Bottom")
		(17 "Dwgs.User" user "User.Drawings")
		(19 "Cmts.User" user "User.Comments")
		(21 "Eco1.User" user "User.Eco1")
		(23 "Eco2.User" user "User.Eco2")
		(25 "Edge.Cuts" user "Board Geometry/Outline")
		(27 "Margin" user)
		(31 "F.CrtYd" user "Package Geometry/Place Bound Top")
		(29 "B.CrtYd" user "Package Geometry/Place Bound Bottom")
		(35 "F.Fab" user "Ref Des/Assembly Top")
		(33 "B.Fab" user "Ref Des/Assembly Bottom")
	)
	(footprint ""
		(layer "F.Cu")
		(at 244.63375 -51.332384 180)
		(property "Reference" "C1110"
			(at 0 0 180)
			(layer "F.SilkS")
			(hide yes)
			(effects
				(font
					(size 1.27 1.27)
				)
			)
		)
		(property "Value" ""
			(at 0 0 180)
			(layer "F.Fab")
			(effects
				(font
					(size 1.27 1.27)
				)
			)
		)
		(duplicate_pad_numbers_are_jumpers no)
		(fp_line
			(start 0.7874 0.4064)
			(end -0.7874 0.4064)
			(stroke
				(width 0.1524)
				(type default)
			)
			(layer "F.SilkS")
		)
		(fp_line
			(start 0.7874 -0.4064)
			(end 0.7874 0.4064)
			(stroke
				(width 0.1524)
				(type default)
			)
			(layer "F.SilkS")
		)
		(fp_line
			(start -0.7874 0.4064)
			(end -0.7874 -0.4064)
			(stroke
				(width 0.1524)
				(type default)
			)
			(layer "F.SilkS")
		)
		(fp_line
			(start -0.7874 -0.4064)
			(end 0.7874 -0.4064)
			(stroke
				(width 0.1524)
				(type default)
			)
			(layer "F.SilkS")
		)
		(fp_line
			(start 0.67945 0.3048)
			(end 0.120396 0.3048)
			(stroke
				(width 0.1)
				(type default)
			)
			(layer "F.Fab")
		)
		(fp_line
			(start 0.67945 -0.3048)
			(end 0.67945 0.3048)
			(stroke
				(width 0.1)
				(type default)
			)
			(layer "F.Fab")
		)
		(fp_line
			(start 0.12065 -0.2794)
			(end 0.12065 -0.3048)
			(stroke
				(width 0.1)
				(type default)
			)
			(layer "F.Fab")
		)
		(fp_line
			(start 0.12065 -0.3048)
			(end 0.67945 -0.3048)
			(stroke
				(width 0.1)
				(type default)
			)
			(layer "F.Fab")
		)
		(fp_line
			(start 0.120396 0.3048)
			(end 0.120396 0.2794)
			(stroke
				(width 0.1)
				(type default)
			)
			(layer "F.Fab")
		)
		(fp_line
			(start 0.120396 0.2794)
			(end -0.12065 0.2794)
			(stroke
				(width 0.1)
				(type default)
			)
			(layer "F.Fab")
		)
		(fp_line
			(start -0.12065 0.3048)
			(end -0.67945 0.3048)
			(stroke
				(width 0.1)
				(type default)
			)
			(layer "F.Fab")
		)
		(fp_line
			(start -0.12065 0.2794)
			(end -0.12065 0.3048)
			(stroke
				(width 0.1)
				(type default)
			)
			(layer "F.Fab")
		)
		(fp_line
			(start -0.12065 -0.2794)
			(end 0.12065 -0.2794)
			(stroke
				(width 0.1)
				(type default)
			)
			(layer "F.Fab")
		)
		(fp_line
			(start -0.12065 -0.305054)
			(end -0.12065 -0.2794)
			(stroke
				(width 0.1)
				(type default)
			)
			(layer "F.Fab")
		)
		(fp_line
			(start -0.67945 0.3048)
			(end -0.67945 -0.305054)
			(stroke
				(width 0.1)
				(type default)
			)
			(layer "F.Fab")
		)
		(fp_line
			(start -0.67945 -0.305054)
			(end -0.12065 -0.305054)
			(stroke
				(width 0.1)
				(type default)
			)
			(layer "F.Fab")
		)
		(pad "1" smd circle
			(at -0.40005 0 180)
			(size 0 0)
			(layers "F.Cu" "F.Mask" "F.Paste")
			(net "VSENSE_P12V_INA230_8_INP")
		)
		(pad "2" smd circle
			(at 0.40005 0 180)
			(size 0 0)
			(layers "F.Cu" "F.Mask" "F.Paste")
			(net "VSENSE_P12V_INA230_8_INN")
		)
	)
	(footprint ""
		(layer "F.Cu")
		(at 320.981324 -192.09766 -90)
		(property "Reference" "R2310"
			(at 0 0 270)
			(layer "F.SilkS")
			(hide yes)
			(effects
				(font
					(size 1.27 1.27)
				)
			)
		)
		(property "Value" ""
			(at 0 0 270)
			(layer "F.Fab")
			(effects
				(font
					(size 1.27 1.27)
				)
			)
		)
		(duplicate_pad_numbers_are_jumpers no)
		(fp_line
			(start -0.7874 0.4064)
			(end -0.7874 -0.4064)
			(stroke
				(width 0.1524)
				(type default)
			)
			(layer "F.SilkS")
		)
		(fp_line
			(start 0.7874 0.4064)
			(end -0.7874 0.4064)
			(stroke
				(width 0.1524)
				(type default)
			)
			(layer "F.SilkS")
		)
		(fp_line
			(start -0.7874 -0.4064)
			(end 0.7874 -0.4064)
			(stroke
				(width 0.1524)
				(type default)
			)
			(layer "F.SilkS")
		)
		(fp_line
			(start 0.7874 -0.4064)
			(end 0.7874 0.4064)
			(stroke
				(width 0.1524)
				(type default)
			)
			(layer "F.SilkS")
		)
		(fp_line
			(start -0.67945 0.3048)
			(end -0.67945 -0.305054)
			(stroke
				(width 0.1)
				(type default)
			)
			(layer "F.Fab")
		)
		(fp_line
			(start -0.12065 0.3048)
			(end -0.67945 0.3048)
			(stroke
				(width 0.1)
				(type default)
			)
			(layer "F.Fab")
		)
		(fp_line
			(start 0.120396 0.3048)
			(end 0.120396 0.2794)
			(stroke
				(width 0.1)
				(type default)
			)
			(layer "F.Fab")
		)
		(fp_line
			(start 0.67945 0.3048)
			(end 0.120396 0.3048)
			(stroke
				(width 0.1)
				(type default)
			)
			(layer "F.Fab")
		)
		(fp_line
			(start -0.12065 0.2794)
			(end -0.12065 0.3048)
			(stroke
				(width 0.1)
				(type default)
			)
			(layer "F.Fab")
		)
		(fp_line
			(start 0.120396 0.2794)
			(end -0.12065 0.2794)
			(stroke
				(width 0.1)
				(type default)
			)
			(layer "F.Fab")
		)
		(fp_line
			(start -0.12065 -0.2794)
			(end 0.12065 -0.2794)
			(stroke
				(width 0.1)
				(type default)
			)
			(layer "F.Fab")
		)
		(fp_line
			(start 0.12065 -0.2794)
			(end 0.12065 -0.3048)
			(stroke
				(width 0.1)
				(type default)
			)
			(layer "F.Fab")
		)
		(fp_line
			(start 0.12065 -0.3048)
			(end 0.67945 -0.3048)
			(stroke
				(width 0.1)
				(type default)
			)
			(layer "F.Fab")
		)
		(fp_line
			(start 0.67945 -0.3048)
			(end 0.67945 0.3048)
			(stroke
				(width 0.1)
				(type default)
			)
			(layer "F.Fab")
		)
		(fp_line
			(start -0.67945 -0.305054)
			(end -0.12065 -0.305054)
			(stroke
				(width 0.1)
				(type default)
			)
			(layer "F.Fab")
		)
		(fp_line
			(start -0.12065 -0.305054)
			(end -0.12065 -0.2794)
			(stroke
				(width 0.1)
				(type default)
			)
			(layer "F.Fab")
		)
		(pad "1" smd rect
			(at -0.40005 0 90)
			(size 0.4572 0.508)
			(layers "F.Cu" "F.Mask" "F.Paste")
			(net "I3C_0_SPD_DDRAF_CPU0_R_SCL")
		)
		(pad "2" smd rect
			(at 0.40005 0 90)
			(size 0.4572 0.508)
			(layers "F.Cu" "F.Mask" "F.Paste")
			(net "I3C_SPD_DDRAF_CPU0_BYPASS_SCL")
		)
	)
	(footprint ""
		(layer "F.Cu")
		(at 319.940178 -45.859954)
		(property "Reference" "C37"
			(at 0 0 0)
			(layer "F.SilkS")
			(hide yes)
			(effects
				(font
					(size 1.27 1.27)
				)
			)
		)
		(property "Value" ""
			(at 0 0 0)
			(layer "F.Fab")
			(effects
				(font
					(size 1.27 1.27)
				)
			)
		)
		(duplicate_pad_numbers_are_jumpers no)
		(fp_line
			(start -0.7874 -0.4064)
			(end 0.7874 -0.4064)
			(stroke
				(width 0.1524)
				(type default)
			)
			(layer "F.SilkS")
		)
		(fp_line
			(start -0.7874 0.4064)
			(end -0.7874 -0.4064)
			(stroke
				(width 0.1524)
				(type default)
			)
			(layer "F.SilkS")
		)
		(fp_line
			(start 0.7874 -0.4064)
			(end 0.7874 0.4064)
			(stroke
				(width 0.1524)
				(type default)
			)
			(layer "F.SilkS")
		)
		(fp_line
			(start 0.7874 0.4064)
			(end -0.7874 0.4064)
			(stroke
				(width 0.1524)
				(type default)
			)
			(layer "F.SilkS")
		)
		(fp_line
			(start -0.67945 -0.305054)
			(end -0.12065 -0.305054)
			(stroke
				(width 0.1)
				(type default)
			)
			(layer "F.Fab")
		)
		(fp_line
			(start -0.67945 0.3048)
			(end -0.67945 -0.305054)
			(stroke
				(width 0.1)
				(type default)
			)
			(layer "F.Fab")
		)
		(fp_line
			(start -0.12065 -0.305054)
			(end -0.12065 -0.2794)
			(stroke
				(width 0.1)
				(type default)
			)
			(layer "F.Fab")
		)
		(fp_line
			(start -0.12065 -0.2794)
			(end 0.12065 -0.2794)
			(stroke
				(width 0.1)
				(type default)
			)
			(layer "F.Fab")
		)
		(fp_line
			(start -0.12065 0.2794)
			(end -0.12065 0.3048)
			(stroke
				(width 0.1)
				(type default)
			)
			(layer "F.Fab")
		)
		(fp_line
			(start -0.12065 0.3048)
			(end -0.67945 0.3048)
			(stroke
				(width 0.1)
				(type default)
			)
			(layer "F.Fab")
		)
		(fp_line
			(start 0.120396 0.2794)
			(end -0.12065 0.2794)
			(stroke
				(width 0.1)
				(type default)
			)
			(layer "F.Fab")
		)
		(fp_line
			(start 0.120396 0.3048)
			(end 0.120396 0.2794)
			(stroke
				(width 0.1)
				(type default)
			)
			(layer "F.Fab")
		)
		(fp_line
			(start 0.12065 -0.3048)
			(end 0.67945 -0.3048)
			(stroke
				(width 0.1)
				(type default)
			)
			(layer "F.Fab")
		)
		(fp_line
			(start 0.12065 -0.2794)
			(end 0.12065 -0.3048)
			(stroke
				(width 0.1)
				(type default)
			)
			(layer "F.Fab")
		)
		(fp_line
			(start 0.67945 -0.3048)
			(end 0.67945 0.3048)
			(stroke
				(width 0.1)
				(type default)
			)
			(layer "F.Fab")
		)
		(fp_line
			(start 0.67945 0.3048)
			(end 0.120396 0.3048)
			(stroke
				(width 0.1)
				(type default)
			)
			(layer "F.Fab")
		)
		(pad "1" smd circle
			(at -0.40005 0)
			(size 0 0)
			(layers "F.Cu" "F.Mask" "F.Paste")
			(net "P12V_OCP_SFF_ISENSE_TIC")
		)
		(pad "2" smd circle
			(at 0.40005 0)
			(size 0 0)
			(layers "F.Cu" "F.Mask" "F.Paste")
			(net "GND")
		)
	)
)
